# BASEBOARD_FAB2 (Tioga Pass) — schematic netlist excerpt (pin names and nets, part order shuffled) for the footprints in the layout excerpt that follows; sources: Cadence DE-HDL packaged netlist, KiCad conversion of Wiwynn_Tioga_Pass_MB.brd

R3P44  RES  4.75K 1% CHIP  pkg 0402  page 196 : A = P3V3_STBY ; B = PWRGD_DSW_PWROK
RF14  RES  1.0K 0.1% CHIP  pkg 0402  page 213 : A = VR_PVCCIO_CPU1_AIREF1 ; B = ISENSE_PVCCIO_CPU1_PH1_IMON
C3M40  CAP  0.22UF 16V 10% X7R  pkg 0402  page 129 : A = DMI_CPU0_PCH_RX_DP<0> ; B = DMI_CPU0_PCH_RX_C_DP<0>

(kicad_pcb
	(version 20260206)
	(generator "pcbnew")
	(generator_version "10.0")
	(general
		(thickness 1.6)
		(legacy_teardrops no)
	)
	(paper "A4")
	(title_block
		(title "Wiwynn_Tioga_Pass_MB.brd")
		(comment 1 "Tioga Pass / footprints 3591-3593 of 4770")
	)
	(layers
		(0 "F.Cu" signal "TOP")
		(4 "In1.Cu" signal "L2GND")
		(6 "In2.Cu" signal "L3")
		(8 "In3.Cu" signal "L4GND")
		(10 "In4.Cu" signal "L5")
		(12 "In5.Cu" signal "L6GND")
		(14 "In6.Cu" signal "L7VCC")
		(16 "In7.Cu" signal "L8VCC")
		(18 "In8.Cu" signal "L9GND")
		(20 "In9.Cu" signal "L10")
		(22 "In10.Cu" signal "L11GND")
		(24 "In11.Cu" signal "L12")
		(26 "In12.Cu" signal "L13GND")
		(2 "B.Cu" signal "BOTTOM")
		(9 "F.Adhes" user "F.Adhesive")
		(11 "B.Adhes" user "B.Adhesive")
		(13 "F.Paste" user "Package Geometry/Pastemask Top")
		(15 "B.Paste" user "Package Geometry/Pastemask Bottom")
		(5 "F.SilkS" user "Ref Des/Silkscreen Top")
		(7 "B.SilkS" user "Ref Des/Silkscreen Bottom")
		(1 "F.Mask" user "Board Geometry/Soldermask Top")
		(3 "B.Mask" user "Board Geometry/Soldermask Bottom")
		(17 "Dwgs.User" user "User.Drawings")
		(19 "Cmts.User" user "User.Comments")
		(21 "Eco1.User" user "User.Eco1")
		(23 "Eco2.User" user "User.Eco2")
		(25 "Edge.Cuts" user "Board Geometry/Outline")
		(27 "Margin" user)
		(31 "F.CrtYd" user "Package Geometry/Place Bound Top")
		(29 "B.CrtYd" user "Package Geometry/Place Bound Bottom")
		(35 "F.Fab" user "Ref Des/Assembly Top")
		(33 "B.Fab" user "Ref Des/Assembly Bottom")
	)
	(footprint ""
		(layer "B.Cu")
		(at 168.529 -65.405)
		(property "Reference" "RF14"
			(at 0.8382 -0.67818 0)
			(unlocked yes)
			(layer "B.SilkS")
			(effects
				(font
					(size 0.4064 0.254)
					(thickness 0.1524)
				)
				(justify left mirror)
			)
		)
		(property "Value" ""
			(at 0 0 0)
			(layer "B.Fab")
			(effects
				(font
					(size 1.27 1.27)
				)
				(justify mirror)
			)
		)
		(duplicate_pad_numbers_are_jumpers no)
		(fp_poly
			(pts
				(xy 0.2794 -0.1016) (xy -0.2794 -0.1016) (xy -0.2794 0.9906) (xy 0.2794 0.9906)
			)
			(stroke
				(width 0)
				(type default)
			)
			(fill no)
			(layer "B.CrtYd")
		)
		(fp_line
			(start -0.2794 -0.1016)
			(end 0.2794 -0.1016)
			(stroke
				(width 0.1)
				(type default)
			)
			(layer "B.Fab")
		)
		(fp_line
			(start -0.2794 0.9906)
			(end -0.2794 -0.1016)
			(stroke
				(width 0.1)
				(type default)
			)
			(layer "B.Fab")
		)
		(fp_line
			(start 0.2794 -0.1016)
			(end 0.2794 0.9906)
			(stroke
				(width 0.1)
				(type default)
			)
			(layer "B.Fab")
		)
		(fp_line
			(start 0.2794 0.9906)
			(end -0.2794 0.9906)
			(stroke
				(width 0.1)
				(type default)
			)
			(layer "B.Fab")
		)
		(pad "1" smd rect
			(at 0 0 180)
			(size 0.508 0.508)
			(layers "B.Cu" "B.Mask" "B.Paste")
			(net "VR_PVCCIO_CPU1_AIREF1")
		)
		(pad "2" smd rect
			(at 0 0.889 180)
			(size 0.508 0.508)
			(layers "B.Cu" "B.Mask" "B.Paste")
			(net "ISENSE_PVCCIO_CPU1_PH1_IMON")
		)
		(zone
			(layer "B.Cu")
			(hatch none 0.5)
			(connect_pads
				(clearance 0)
			)
			(min_thickness 0.25)
			(keepout
				(tracks allowed)
				(vias not_allowed)
				(pads allowed)
				(copperpour not_allowed)
				(footprints allowed)
			)
			(placement
				(enabled no)
				(sheetname "")
			)
			(fill
				(thermal_gap 0.5)
				(thermal_bridge_width 0.5)
				(island_removal_mode 0)
			)
			(polygon
				(pts
					(xy 168.783 -65.151) (xy 168.275 -65.151) (xy 168.275 -64.77) (xy 168.783 -64.77)
				)
			)
		)
		(zone
			(layer "B.Cu")
			(hatch none 0.5)
			(connect_pads
				(clearance 0)
			)
			(min_thickness 0.25)
			(keepout
				(tracks not_allowed)
				(vias allowed)
				(pads allowed)
				(copperpour not_allowed)
				(footprints allowed)
			)
			(placement
				(enabled no)
				(sheetname "")
			)
			(fill
				(thermal_gap 0.5)
				(thermal_bridge_width 0.5)
				(island_removal_mode 0)
			)
			(polygon
				(pts
					(xy 168.783 -64.77) (xy 168.275 -64.77) (xy 168.275 -65.151) (xy 168.783 -65.151)
				)
			)
		)
	)
	(footprint ""
		(layer "B.Cu")
		(at 369.443 -113.792 -90)
		(property "Reference" "C3M40"
			(at 0 0 90)
			(layer "B.SilkS")
			(hide yes)
			(effects
				(font
					(size 1.27 1.27)
				)
				(justify mirror)
			)
		)
		(property "Value" ""
			(at 0 0 90)
			(layer "B.Fab")
			(effects
				(font
					(size 1.27 1.27)
				)
				(justify mirror)
			)
		)
		(duplicate_pad_numbers_are_jumpers no)
		(fp_poly
			(pts
				(xy -0.3048 -0.1016) (xy -0.3048 0.9906) (xy 0.3048 0.9906) (xy 0.3048 -0.1016)
			)
			(stroke
				(width 0)
				(type default)
			)
			(fill no)
			(layer "B.CrtYd")
		)
		(fp_line
			(start -0.3048 0.9906)
			(end -0.3048 -0.1016)
			(stroke
				(width 0.1)
				(type default)
			)
			(layer "B.Fab")
		)
		(fp_line
			(start 0.3048 0.9906)
			(end -0.3048 0.9906)
			(stroke
				(width 0.1)
				(type default)
			)
			(layer "B.Fab")
		)
		(fp_line
			(start -0.3048 -0.1016)
			(end 0.3048 -0.1016)
			(stroke
				(width 0.1)
				(type default)
			)
			(layer "B.Fab")
		)
		(fp_line
			(start 0.3048 -0.1016)
			(end 0.3048 0.9906)
			(stroke
				(width 0.1)
				(type default)
			)
			(layer "B.Fab")
		)
		(pad "1" smd rect
			(at 0 0 90)
			(size 0.508 0.508)
			(layers "B.Cu" "B.Mask" "B.Paste")
			(net "DMI_CPU0_PCH_RX_DP<0>")
		)
		(pad "2" smd rect
			(at 0 0.889 90)
			(size 0.508 0.508)
			(layers "B.Cu" "B.Mask" "B.Paste")
			(net "DMI_CPU0_PCH_RX_C_DP<0>")
		)
		(zone
			(layer "B.Cu")
			(hatch none 0.5)
			(connect_pads
				(clearance 0)
			)
			(min_thickness 0.25)
			(keepout
				(tracks not_allowed)
				(vias allowed)
				(pads allowed)
				(copperpour not_allowed)
				(footprints allowed)
			)
			(placement
				(enabled no)
				(sheetname "")
			)
			(fill
				(thermal_gap 0.5)
				(thermal_bridge_width 0.5)
				(island_removal_mode 0)
			)
			(polygon
				(pts
					(xy 368.808 -113.538) (xy 368.808 -114.046) (xy 369.189 -114.046) (xy 369.189 -113.538)
				)
			)
		)
		(zone
			(layer "B.Cu")
			(hatch none 0.5)
			(connect_pads
				(clearance 0)
			)
			(min_thickness 0.25)
			(keepout
				(tracks allowed)
				(vias not_allowed)
				(pads allowed)
				(copperpour not_allowed)
				(footprints allowed)
			)
			(placement
				(enabled no)
				(sheetname "")
			)
			(fill
				(thermal_gap 0.5)
				(thermal_bridge_width 0.5)
				(island_removal_mode 0)
			)
			(polygon
				(pts
					(xy 369.189 -113.538) (xy 369.189 -114.046) (xy 368.808 -114.046) (xy 368.808 -113.538)
				)
			)
		)
	)
	(footprint ""
		(layer "B.Cu")
		(at 422.8465 -4.191 -90)
		(property "Reference" "R3P44"
			(at 0 0 90)
			(layer "B.SilkS")
			(hide yes)
			(effects
				(font
					(size 1.27 1.27)
				)
				(justify mirror)
			)
		)
		(property "Value" ""
			(at 0 0 90)
			(layer "B.Fab")
			(effects
				(font
					(size 1.27 1.27)
				)
				(justify mirror)
			)
		)
		(duplicate_pad_numbers_are_jumpers no)
		(fp_rect
			(start 0.2794 -0.1016)
			(end -0.2794 0.9906)
			(stroke
				(width 0)
				(type default)
			)
			(fill no)
			(layer "B.CrtYd")
		)
		(fp_line
			(start -0.2794 0.9906)
			(end -0.2794 -0.1016)
			(stroke
				(width 0.1)
				(type default)
			)
			(layer "B.Fab")
		)
		(fp_line
			(start 0.2794 0.9906)
			(end -0.2794 0.9906)
			(stroke
				(width 0.1)
				(type default)
			)
			(layer "B.Fab")
		)
		(fp_line
			(start -0.2794 -0.1016)
			(end 0.2794 -0.1016)
			(stroke
				(width 0.1)
				(type default)
			)
			(layer "B.Fab")
		)
		(fp_line
			(start 0.2794 -0.1016)
			(end 0.2794 0.9906)
			(stroke
				(width 0.1)
				(type default)
			)
			(layer "B.Fab")
		)
		(pad "1" smd rect
			(at 0 0 90)
			(size 0.508 0.508)
			(layers "B.Cu" "B.Mask" "B.Paste")
			(net "P3V3_STBY")
		)
		(pad "2" smd rect
			(at 0 0.889 90)
			(size 0.508 0.508)
			(layers "B.Cu" "B.Mask" "B.Paste")
			(net "PWRGD_DSW_PWROK")
		)
		(zone
			(layer "B.Cu")
			(hatch none 0.5)
			(connect_pads
				(clearance 0)
			)
			(min_thickness 0.25)
			(keepout
				(tracks allowed)
				(vias not_allowed)
				(pads allowed)
				(copperpour not_allowed)
				(footprints allowed)
			)
			(placement
				(enabled no)
				(sheetname "")
			)
			(fill
				(thermal_gap 0.5)
				(thermal_bridge_width 0.5)
				(island_removal_mode 0)
			)
			(polygon
				(pts
					(xy 422.5925 -3.937) (xy 422.5925 -4.445) (xy 422.2115 -4.445) (xy 422.2115 -3.937)
				)
			)
		)
		(zone
			(layer "B.Cu")
			(hatch none 0.5)
			(connect_pads
				(clearance 0)
			)
			(min_thickness 0.25)
			(keepout
				(tracks not_allowed)
				(vias allowed)
				(pads allowed)
				(copperpour not_allowed)
				(footprints allowed)
			)
			(placement
				(enabled no)
				(sheetname "")
			)
			(fill
				(thermal_gap 0.5)
				(thermal_bridge_width 0.5)
				(island_removal_mode 0)
			)
			(polygon
				(pts
					(xy 422.5925 -3.937) (xy 422.5925 -4.445) (xy 422.2115 -4.445) (xy 422.2115 -3.937)
				)
			)
		)
	)
)
